(kicad_pcb
	(version 20260206)
	(generator "pcbnew")
	(generator_version "10.0")
	(general
		(thickness 1.6)
		(legacy_teardrops no)
	)
	(paper "A4")
	(title_block
		(title "Bryce Canyon_F.DPB_16315-1-OCP.brd")
		(comment 1 "Bryce Canyon / footprints 2133-2140 of 2223")
	)
	(layers
		(0 "F.Cu" signal "TOP")
		(4 "In1.Cu" signal "L2GND")
		(6 "In2.Cu" signal "L3")
		(8 "In3.Cu" signal "L4GND")
		(10 "In4.Cu" signal "L5")
		(12 "In5.Cu" signal "L6VCC")
		(14 "In6.Cu" signal "L7VCC")
		(16 "In7.Cu" signal "L8")
		(18 "In8.Cu" signal "L9GND")
		(20 "In9.Cu" signal "L10")
		(22 "In10.Cu" signal "L11GND")
		(2 "B.Cu" signal "BOTTOM")
		(9 "F.Adhes" user "F.Adhesive")
		(11 "B.Adhes" user "B.Adhesive")
		(13 "F.Paste" user "Package Geometry/Pastemask Top")
		(15 "B.Paste" user "Package Geometry/Pastemask Bottom")
		(5 "F.SilkS" user "Ref Des/Silkscreen Top")
		(7 "B.SilkS" user "Ref Des/Silkscreen Bottom")
		(1 "F.Mask" user "Board Geometry/Soldermask Top")
		(3 "B.Mask" user "Board Geometry/Soldermask Bottom")
		(17 "Dwgs.User" user "User.Drawings")
		(19 "Cmts.User" user "User.Comments")
		(21 "Eco1.User" user "User.Eco1")
		(23 "Eco2.User" user "User.Eco2")
		(25 "Edge.Cuts" user "Board Geometry/Outline")
		(27 "Margin" user)
		(31 "F.CrtYd" user "Package Geometry/Place Bound Top")
		(29 "B.CrtYd" user "Package Geometry/Place Bound Bottom")
		(35 "F.Fab" user "Ref Des/Assembly Top")
		(33 "B.Fab" user "Ref Des/Assembly Bottom")
	)
	(footprint ""
		(layer "B.Cu")
		(at 471.885518 -207.34909 -90)
		(property "Reference" "C663"
			(at 0 0 90)
			(layer "B.SilkS")
			(hide yes)
			(effects
				(font
					(size 1.27 1.27)
				)
				(justify mirror)
			)
		)
		(property "Value" "SC10U16V5KX-7-GP-U"
			(at 0.0762 -6.1214 270)
			(unlocked yes)
			(layer "B.Fab")
			(hide yes)
			(effects
				(font
					(size 1.016 1.016)
					(thickness 0.1524)
				)
				(justify mirror)
			)
		)
		(property "Device Type" "C805H58"
			(at 0.0762 -8.1534 270)
			(unlocked yes)
			(layer "B.Fab")
			(hide yes)
			(effects
				(font
					(size 1.016 1.016)
					(thickness 0.1524)
				)
				(justify mirror)
			)
		)
		(duplicate_pad_numbers_are_jumpers no)
		(fp_line
			(start -0.635 0)
			(end 0.635 0)
			(stroke
				(width 0.508)
				(type default)
			)
			(layer "B.SilkS")
		)
		(fp_rect
			(start 0.9652 1.778)
			(end -0.9652 -1.778)
			(stroke
				(width 0)
				(type default)
			)
			(fill no)
			(layer "B.CrtYd")
		)
		(fp_poly
			(pts
				(xy 0.9652 -1.778) (xy -0.9652 -1.778) (xy -0.9652 1.778) (xy 0.9652 1.778)
			)
			(stroke
				(width 0)
				(type default)
			)
			(fill no)
			(layer "B.Fab")
		)
		(pad "1" smd rect
			(at 0 -0.9652 90)
			(size 1.397 1.143)
			(layers "B.Cu" "B.Mask" "B.Paste")
			(net "P5V_A_4")
		)
		(pad "2" smd rect
			(at 0 0.9652 90)
			(size 1.397 1.143)
			(layers "B.Cu" "B.Mask" "B.Paste")
			(net "GND")
		)
	)
	(footprint ""
		(layer "B.Cu")
		(at 470.939622 -213.114128 -90)
		(property "Reference" "TC12"
			(at 0 0 90)
			(layer "B.SilkS")
			(hide yes)
			(effects
				(font
					(size 1.27 1.27)
				)
				(justify mirror)
			)
		)
		(property "Value" "ST220U10VDM-LGP"
			(at 0 -9.6012 270)
			(unlocked yes)
			(layer "B.Fab")
			(hide yes)
			(effects
				(font
					(size 1.016 1.016)
					(thickness 0.1524)
				)
				(justify mirror)
			)
		)
		(property "Device Type" "CT7343H119"
			(at 0 -11.1252 270)
			(unlocked yes)
			(layer "B.Fab")
			(hide yes)
			(effects
				(font
					(size 1.016 1.016)
					(thickness 0.1524)
				)
				(justify mirror)
			)
		)
		(duplicate_pad_numbers_are_jumpers no)
		(fp_line
			(start -2.286 4.8768)
			(end 2.286 4.8768)
			(stroke
				(width 0.1524)
				(type default)
			)
			(layer "B.SilkS")
		)
		(fp_line
			(start 2.286 4.8768)
			(end 2.286 2.032)
			(stroke
				(width 0.1524)
				(type default)
			)
			(layer "B.SilkS")
		)
		(fp_line
			(start -2.286 2.032)
			(end -2.286 4.8768)
			(stroke
				(width 0.1524)
				(type default)
			)
			(layer "B.SilkS")
		)
		(fp_line
			(start -2.286 -2.032)
			(end -2.286 -4.8768)
			(stroke
				(width 0.1524)
				(type default)
			)
			(layer "B.SilkS")
		)
		(fp_line
			(start -2.1082 -4.699)
			(end 2.1082 -4.699)
			(stroke
				(width 0.508)
				(type default)
			)
			(layer "B.SilkS")
		)
		(fp_line
			(start -2.286 -4.8768)
			(end 2.286 -4.8768)
			(stroke
				(width 0.1524)
				(type default)
			)
			(layer "B.SilkS")
		)
		(fp_line
			(start 2.286 -4.8768)
			(end 2.286 -2.032)
			(stroke
				(width 0.1524)
				(type default)
			)
			(layer "B.SilkS")
		)
		(fp_rect
			(start 2.1463 3.6449)
			(end -2.1463 -3.6449)
			(stroke
				(width 0)
				(type default)
			)
			(fill no)
			(layer "B.CrtYd")
		)
		(fp_poly
			(pts
				(xy 2.54 4.953) (xy 2.54 4.2926) (xy 3.81 4.2926) (xy 3.81 -4.2926) (xy 2.54 -4.2926) (xy 2.54 -4.953)
				(xy -2.54 -4.953) (xy -2.54 -4.2926) (xy -3.81 -4.2926) (xy -3.81 -1.6256) (xy -2.1463 -1.6256)
				(xy -2.1463 -3.6449) (xy 2.1463 -3.6449) (xy 2.1463 3.6449) (xy -2.1463 3.6449) (xy -2.1463 -1.6129)
				(xy -3.81 -1.6129) (xy -3.81 4.2926) (xy -2.54 4.2926) (xy -2.54 4.953)
			)
			(stroke
				(width 0)
				(type default)
			)
			(fill no)
			(layer "B.CrtYd")
		)
		(fp_rect
			(start 2.54 4.953)
			(end -2.54 -4.953)
			(stroke
				(width 0)
				(type default)
			)
			(fill no)
			(layer "B.Fab")
		)
		(fp_rect
			(start -2.54 4.2926)
			(end -3.81 -4.2926)
			(stroke
				(width 0)
				(type default)
			)
			(fill no)
			(layer "B.Fab")
		)
		(fp_rect
			(start 3.81 4.2926)
			(end 2.54 -4.2926)
			(stroke
				(width 0)
				(type default)
			)
			(fill no)
			(layer "B.Fab")
		)
		(pad "1" smd rect
			(at 0 -3.1496 90)
			(size 2.413 2.286)
			(layers "B.Cu" "B.Mask" "B.Paste")
			(net "P5V_A_4")
		)
		(pad "2" smd rect
			(at 0 3.1496 90)
			(size 2.413 2.286)
			(layers "B.Cu" "B.Mask" "B.Paste")
			(net "GND")
		)
		(zone
			(layer "B.Cu")
			(hatch none 0.5)
			(connect_pads
				(clearance 0)
			)
			(min_thickness 0.25)
			(keepout
				(tracks allowed)
				(vias not_allowed)
				(pads allowed)
				(copperpour not_allowed)
				(footprints allowed)
			)
			(placement
				(enabled no)
				(sheetname "")
			)
			(fill
				(thermal_gap 0.5)
				(thermal_bridge_width 0.5)
				(island_removal_mode 0)
			)
			(polygon
				(pts
					(xy 466.342222 -211.602828) (xy 466.342222 -214.625428) (xy 469.237822 -214.625428) (xy 469.568022 -214.625428)
					(xy 469.568022 -211.602828) (xy 469.237822 -211.602828)
				)
			)
		)
		(zone
			(layer "B.Cu")
			(hatch none 0.5)
			(connect_pads
				(clearance 0)
			)
			(min_thickness 0.25)
			(keepout
				(tracks allowed)
				(vias not_allowed)
				(pads allowed)
				(copperpour not_allowed)
				(footprints allowed)
			)
			(placement
				(enabled no)
				(sheetname "")
			)
			(fill
				(thermal_gap 0.5)
				(thermal_bridge_width 0.5)
				(island_removal_mode 0)
			)
			(polygon
				(pts
					(xy 472.628722 -214.625428) (xy 475.537022 -214.625428) (xy 475.537022 -211.602828) (xy 472.641422 -211.602828)
					(xy 472.311222 -211.602828) (xy 472.311222 -214.625428)
				)
			)
		)
	)
	(footprint ""
		(layer "B.Cu")
		(at 452.025004 -256.474214 -90)
		(property "Reference" "R1254"
			(at 0 0 90)
			(layer "B.SilkS")
			(hide yes)
			(effects
				(font
					(size 1.27 1.27)
				)
				(justify mirror)
			)
		)
		(property "Value" "10R3F-GP"
			(at 0.0254 -2.5146 270)
			(unlocked yes)
			(layer "B.Fab")
			(hide yes)
			(effects
				(font
					(size 1.016 1.016)
					(thickness 0.1524)
				)
				(justify mirror)
			)
		)
		(property "Device Type" "R603H22"
			(at 0.0254 -4.0386 270)
			(unlocked yes)
			(layer "B.Fab")
			(hide yes)
			(effects
				(font
					(size 1.016 1.016)
					(thickness 0.1524)
				)
				(justify mirror)
			)
		)
		(duplicate_pad_numbers_are_jumpers no)
		(fp_line
			(start -0.2032 0)
			(end -0.4826 0)
			(stroke
				(width 0.2032)
				(type default)
			)
			(layer "B.SilkS")
		)
		(fp_line
			(start 0.4826 0)
			(end 0.2032 0)
			(stroke
				(width 0.2032)
				(type default)
			)
			(layer "B.SilkS")
		)
		(fp_rect
			(start 0.5842 1.3335)
			(end -0.5842 -1.3335)
			(stroke
				(width 0)
				(type default)
			)
			(fill no)
			(layer "B.CrtYd")
		)
		(fp_rect
			(start 0.5842 1.3335)
			(end -0.5842 -1.3335)
			(stroke
				(width 0)
				(type default)
			)
			(fill no)
			(layer "B.Fab")
		)
		(pad "1" smd custom
			(at 0 -0.762 90)
			(size 0.2159 0.2159)
			(layers "B.Cu" "B.Mask" "B.Paste")
			(net "P5V_C_CC")
			(options
				(clearance outline)
				(anchor circle)
			)
			(primitives
				(gr_poly
					(pts
						(arc
							(start -0.3302 0.4318)
							(mid -0.402042 0.402042)
							(end -0.4318 0.3302)
						)
						(arc
							(start -0.4318 -0.3302)
							(mid -0.402042 -0.402042)
							(end -0.3302 -0.4318)
						)
						(arc
							(start 0.3302 -0.4318)
							(mid 0.402042 -0.402042)
							(end 0.4318 -0.3302)
						)
						(arc
							(start 0.4318 0.3302)
							(mid 0.402042 0.402042)
							(end 0.3302 0.4318)
						)
					)
					(width 0)
					(fill yes)
				)
			)
		)
		(pad "2" smd custom
			(at 0 0.762 90)
			(size 0.2159 0.2159)
			(layers "B.Cu" "B.Mask" "B.Paste")
			(net "P5V_C_VFB_R")
			(options
				(clearance outline)
				(anchor circle)
			)
			(primitives
				(gr_poly
					(pts
						(arc
							(start -0.3302 0.4318)
							(mid -0.402042 0.402042)
							(end -0.4318 0.3302)
						)
						(arc
							(start -0.4318 -0.3302)
							(mid -0.402042 -0.402042)
							(end -0.3302 -0.4318)
						)
						(arc
							(start 0.3302 -0.4318)
							(mid 0.402042 -0.402042)
							(end 0.4318 -0.3302)
						)
						(arc
							(start 0.4318 0.3302)
							(mid 0.402042 0.402042)
							(end 0.3302 0.4318)
						)
					)
					(width 0)
					(fill yes)
				)
			)
		)
	)
	(footprint ""
		(layer "B.Cu")
		(at 470.408 -239.395 -90)
		(property "Reference" "C652"
			(at 0 0 90)
			(layer "B.SilkS")
			(hide yes)
			(effects
				(font
					(size 1.27 1.27)
				)
				(justify mirror)
			)
		)
		(property "Value" "SC10U16V5KX-7-GP-U"
			(at 0.0762 -6.1214 270)
			(unlocked yes)
			(layer "B.Fab")
			(hide yes)
			(effects
				(font
					(size 1.016 1.016)
					(thickness 0.1524)
				)
				(justify mirror)
			)
		)
		(property "Device Type" "C805H58"
			(at 0.0762 -8.1534 270)
			(unlocked yes)
			(layer "B.Fab")
			(hide yes)
			(effects
				(font
					(size 1.016 1.016)
					(thickness 0.1524)
				)
				(justify mirror)
			)
		)
		(duplicate_pad_numbers_are_jumpers no)
		(fp_line
			(start -0.635 0)
			(end 0.635 0)
			(stroke
				(width 0.508)
				(type default)
			)
			(layer "B.SilkS")
		)
		(fp_rect
			(start 0.9652 1.778)
			(end -0.9652 -1.778)
			(stroke
				(width 0)
				(type default)
			)
			(fill no)
			(layer "B.CrtYd")
		)
		(fp_poly
			(pts
				(xy 0.9652 -1.778) (xy -0.9652 -1.778) (xy -0.9652 1.778) (xy 0.9652 1.778)
			)
			(stroke
				(width 0)
				(type default)
			)
			(fill no)
			(layer "B.Fab")
		)
		(pad "1" smd rect
			(at 0 -0.9652 90)
			(size 1.397 1.143)
			(layers "B.Cu" "B.Mask" "B.Paste")
			(net "P12V_A_VIN_U27")
		)
		(pad "2" smd rect
			(at 0 0.9652 90)
			(size 1.397 1.143)
			(layers "B.Cu" "B.Mask" "B.Paste")
			(net "GND")
		)
	)
	(footprint ""
		(layer "B.Cu")
		(at 39.863014 -252.893576 180)
		(property "Reference" "C608"
			(at 0 0 0)
			(layer "B.SilkS")
			(hide yes)
			(effects
				(font
					(size 1.27 1.27)
				)
				(justify mirror)
			)
		)
		(property "Value" "SCD1U50V3KX-GP"
			(at 0 -2.8194 180)
			(unlocked yes)
			(layer "B.Fab")
			(hide yes)
			(effects
				(font
					(size 1.016 1.016)
					(thickness 0.1524)
				)
				(justify mirror)
			)
		)
		(property "Device Type" "C603H36"
			(at 0 -4.3434 180)
			(unlocked yes)
			(layer "B.Fab")
			(hide yes)
			(effects
				(font
					(size 1.016 1.016)
					(thickness 0.1524)
				)
				(justify mirror)
			)
		)
		(duplicate_pad_numbers_are_jumpers no)
		(fp_line
			(start -0.508 0)
			(end 0.508 0)
			(stroke
				(width 0.2032)
				(type default)
			)
			(layer "B.SilkS")
		)
		(fp_rect
			(start 0.5842 1.3335)
			(end -0.5842 -1.3335)
			(stroke
				(width 0)
				(type default)
			)
			(fill no)
			(layer "B.CrtYd")
		)
		(fp_rect
			(start 0.5842 1.3335)
			(end -0.5842 -1.3335)
			(stroke
				(width 0)
				(type default)
			)
			(fill no)
			(layer "B.Fab")
		)
		(pad "1" smd custom
			(at 0 -0.762)
			(size 0.2159 0.2159)
			(layers "B.Cu" "B.Mask" "B.Paste")
			(net "P5V_A_1")
			(options
				(clearance outline)
				(anchor circle)
			)
			(primitives
				(gr_poly
					(pts
						(arc
							(start -0.3302 0.4318)
							(mid -0.402042 0.402042)
							(end -0.4318 0.3302)
						)
						(arc
							(start -0.4318 -0.3302)
							(mid -0.402042 -0.402042)
							(end -0.3302 -0.4318)
						)
						(arc
							(start 0.3302 -0.4318)
							(mid 0.402042 -0.402042)
							(end 0.4318 -0.3302)
						)
						(arc
							(start 0.4318 0.3302)
							(mid 0.402042 0.402042)
							(end 0.3302 0.4318)
						)
					)
					(width 0)
					(fill yes)
				)
			)
		)
		(pad "2" smd custom
			(at 0 0.762)
			(size 0.2159 0.2159)
			(layers "B.Cu" "B.Mask" "B.Paste")
			(net "P5V_A_LL_R")
			(options
				(clearance outline)
				(anchor circle)
			)
			(primitives
				(gr_poly
					(pts
						(arc
							(start -0.3302 0.4318)
							(mid -0.402042 0.402042)
							(end -0.4318 0.3302)
						)
						(arc
							(start -0.4318 -0.3302)
							(mid -0.402042 -0.402042)
							(end -0.3302 -0.4318)
						)
						(arc
							(start 0.3302 -0.4318)
							(mid 0.402042 -0.402042)
							(end 0.4318 -0.3302)
						)
						(arc
							(start 0.4318 0.3302)
							(mid 0.402042 0.402042)
							(end 0.3302 0.4318)
						)
					)
					(width 0)
					(fill yes)
				)
			)
		)
	)
	(footprint ""
		(layer "B.Cu")
		(at 35.1028 -142.1384 180)
		(property "Reference" "C619"
			(at 0 0 0)
			(layer "B.SilkS")
			(hide yes)
			(effects
				(font
					(size 1.27 1.27)
				)
				(justify mirror)
			)
		)
		(property "Value" "SC10U16V5KX-7-GP-U"
			(at 0.0762 -6.1214 180)
			(unlocked yes)
			(layer "B.Fab")
			(hide yes)
			(effects
				(font
					(size 1.016 1.016)
					(thickness 0.1524)
				)
				(justify mirror)
			)
		)
		(property "Device Type" "C805H58"
			(at 0.0762 -8.1534 180)
			(unlocked yes)
			(layer "B.Fab")
			(hide yes)
			(effects
				(font
					(size 1.016 1.016)
					(thickness 0.1524)
				)
				(justify mirror)
			)
		)
		(duplicate_pad_numbers_are_jumpers no)
		(fp_line
			(start -0.635 0)
			(end 0.635 0)
			(stroke
				(width 0.508)
				(type default)
			)
			(layer "B.SilkS")
		)
		(fp_rect
			(start 0.9652 1.778)
			(end -0.9652 -1.778)
			(stroke
				(width 0)
				(type default)
			)
			(fill no)
			(layer "B.CrtYd")
		)
		(fp_poly
			(pts
				(xy 0.9652 -1.778) (xy -0.9652 -1.778) (xy -0.9652 1.778) (xy 0.9652 1.778)
			)
			(stroke
				(width 0)
				(type default)
			)
			(fill no)
			(layer "B.Fab")
		)
		(pad "1" smd rect
			(at 0 -0.9652)
			(size 1.397 1.143)
			(layers "B.Cu" "B.Mask" "B.Paste")
			(net "P12V_A_VIN_U21")
		)
		(pad "2" smd rect
			(at 0 0.9652)
			(size 1.397 1.143)
			(layers "B.Cu" "B.Mask" "B.Paste")
			(net "GND")
		)
	)
	(footprint ""
		(layer "B.Cu")
		(at 219.9894 -123.4694)
		(property "Reference" "R450"
			(at 0 0 0)
			(layer "B.SilkS")
			(hide yes)
			(effects
				(font
					(size 1.27 1.27)
				)
				(justify mirror)
			)
		)
		(property "Value" "0R2J-2-GP"
			(at -0.064008 -3.993896 0)
			(unlocked yes)
			(layer "B.Fab")
			(hide yes)
			(effects
				(font
					(size 1.016 1.016)
					(thickness 0.1524)
				)
				(justify mirror)
			)
		)
		(property "Device Type" "R402H16"
			(at -0.064008 -5.517896 0)
			(unlocked yes)
			(layer "B.Fab")
			(hide yes)
			(effects
				(font
					(size 1.016 1.016)
					(thickness 0.1524)
				)
				(justify mirror)
			)
		)
		(duplicate_pad_numbers_are_jumpers no)
		(fp_line
			(start -0.508 -0.9398)
			(end 0.508 -0.9398)
			(stroke
				(width 0.1524)
				(type default)
			)
			(layer "B.SilkS")
		)
		(fp_line
			(start 0.508 -0.9398)
			(end 0.508 0.9398)
			(stroke
				(width 0.1524)
				(type default)
			)
			(layer "B.SilkS")
		)
		(fp_rect
			(start 0.508 0.9398)
			(end -0.508 -0.9398)
			(stroke
				(width 0)
				(type default)
			)
			(fill no)
			(layer "B.CrtYd")
		)
		(fp_rect
			(start 0.508 0.9398)
			(end -0.508 -0.9398)
			(stroke
				(width 0)
				(type default)
			)
			(fill no)
			(layer "B.Fab")
		)
		(pad "1" smd custom
			(at 0 -0.4445 180)
			(size 0.1397 0.1397)
			(layers "B.Cu" "B.Mask" "B.Paste")
			(net "I2C_BMC_A_COMP_A_SCL_R")
			(options
				(clearance outline)
				(anchor circle)
			)
			(primitives
				(gr_poly
					(pts
						(arc
							(start -0.1778 0.2794)
							(mid -0.249642 0.249642)
							(end -0.2794 0.1778)
						)
						(arc
							(start -0.2794 -0.1778)
							(mid -0.249642 -0.249642)
							(end -0.1778 -0.2794)
						)
						(arc
							(start 0.1778 -0.2794)
							(mid 0.249642 -0.249642)
							(end 0.2794 -0.1778)
						)
						(arc
							(start 0.2794 0.1778)
							(mid 0.249642 0.249642)
							(end 0.1778 0.2794)
						)
					)
					(width 0)
					(fill yes)
				)
			)
		)
		(pad "2" smd custom
			(at 0 0.4445 180)
			(size 0.1397 0.1397)
			(layers "B.Cu" "B.Mask" "B.Paste")
			(net "I2C_BMC_A_COMP_A_SCL_BUF")
			(options
				(clearance outline)
				(anchor circle)
			)
			(primitives
				(gr_poly
					(pts
						(arc
							(start -0.1778 0.2794)
							(mid -0.249642 0.249642)
							(end -0.2794 0.1778)
						)
						(arc
							(start -0.2794 -0.1778)
							(mid -0.249642 -0.249642)
							(end -0.1778 -0.2794)
						)
						(arc
							(start 0.1778 -0.2794)
							(mid 0.249642 -0.249642)
							(end 0.2794 -0.1778)
						)
						(arc
							(start 0.2794 0.1778)
							(mid 0.249642 0.249642)
							(end 0.1778 0.2794)
						)
					)
					(width 0)
					(fill yes)
				)
			)
		)
	)
	(footprint ""
		(layer "B.Cu")
		(at 73.0758 -147.5486 180)
		(property "Reference" "C628"
			(at 0 0 0)
			(layer "B.SilkS")
			(hide yes)
			(effects
				(font
					(size 1.27 1.27)
				)
				(justify mirror)
			)
		)
		(property "Value" "SC10U16V5KX-7-GP-U"
			(at 0.0762 -6.1214 180)
			(unlocked yes)
			(layer "B.Fab")
			(hide yes)
			(effects
				(font
					(size 1.016 1.016)
					(thickness 0.1524)
				)
				(justify mirror)
			)
		)
		(property "Device Type" "C805H58"
			(at 0.0762 -8.1534 180)
			(unlocked yes)
			(layer "B.Fab")
			(hide yes)
			(effects
				(font
					(size 1.016 1.016)
					(thickness 0.1524)
				)
				(justify mirror)
			)
		)
		(duplicate_pad_numbers_are_jumpers no)
		(fp_line
			(start -0.635 0)
			(end 0.635 0)
			(stroke
				(width 0.508)
				(type default)
			)
			(layer "B.SilkS")
		)
		(fp_rect
			(start 0.9652 1.778)
			(end -0.9652 -1.778)
			(stroke
				(width 0)
				(type default)
			)
			(fill no)
			(layer "B.CrtYd")
		)
		(fp_poly
			(pts
				(xy 0.9652 -1.778) (xy -0.9652 -1.778) (xy -0.9652 1.778) (xy 0.9652 1.778)
			)
			(stroke
				(width 0)
				(type default)
			)
			(fill no)
			(layer "B.Fab")
		)
		(pad "1" smd rect
			(at 0 -0.9652)
			(size 1.397 1.143)
			(layers "B.Cu" "B.Mask" "B.Paste")
			(net "P5V_A_2")
		)
		(pad "2" smd rect
			(at 0 0.9652)
			(size 1.397 1.143)
			(layers "B.Cu" "B.Mask" "B.Paste")
			(net "GND")
		)
	)
)
